FILE_TYPE = CONNECTIVITY;
{Allegro Design Entry HDL 17.4-2019 S026 (4007227) 1/17/2022}
"PAGE_NUMBER" = 379;
0"NC";
1"GND\g";
2"P3V3_AUX\g";
3"P3V3_9ZXL045_P1_VDDR\g";
4"GND\g";
5"P3V3_9ZXL045_P1_VDDA\g";
6"P3V3_AUX\g";
7"P3V3_AUX\g";
8"CLK_100M_RETIMER_CPU1_P1_R_DN";
9"CLK_100M_RETIMER_CPU1_P0_R_DP";
10"CLK_9ZXL045_P1_HIBW";
11"P3V3_9ZXL045_P1";
12"GND\g";
13"P3V3_9ZXL045_P1_VDD\g";
14"GND\g";
15"GND\g";
16"P3V3_9ZXL045_P1_VDD\g";
17"P3V3_9ZXL045_P1_VDDA\g";
18"P3V3_9ZXL045_P1_VDDR\g";
19"GND\g";
20"P3V3_AUX\g";
21"GND\g";
22"P3V3_AUX\g";
23"FM_9ZXL045_P1_DEV_EN";
24"FM_9ZXL045_P1_3_OE_N";
25"FM_9ZXL045_P1_2_OE_N";
26"FM_9ZXL045_P1_1_OE_N";
27"NC_U10_NC0";
28"NC_U10_NC3";
29"FM_9ZXL045_P1_0_OE_N";
30"CLK_100M_RETIMER_CPU1_P3_R_DN";
31"NC_U10_FBOUT_N";
32"NC_U10_FBOUT";
33"SMB_9ZXL045_P1_SCL";
34"SMB_9ZXL045_P1_SDA";
35"CLK_9ZXL045_P1_SADR0";
36"CLK_100M_CPU1_CLK13_DN";
37"CLK_100M_CPU1_CLK13_DP";
38"CLK_100M_RETIMER_CPU1_P1_R_DP";
39"NC_U10_NC2";
40"NC_U10_NC1";
41"CLK_9ZXL045_P1_SADR0";
42"CLK_100M_RETIMER_CPU1_P0_R_DN";
43"CLK_100M_RETIMER_CPU1_P2_R_DP";
44"CLK_100M_RETIMER_CPU1_P3_R_DP";
45"CLK_100M_RETIMER_CPU1_P2_R_DN";
46"CLK_9ZXL045_P1_HIBW";
%"UNIVERSAL_POWER"
"1","(-8875,5925)","0","pure_quanta_power","I1";
;
HDL_POWER"P3V3_AUX"
CDS_LIB"pure_quanta_power";
"A"20;
%"Q_RES"
"2","(-3925,1100)","0","pure_quanta","I15";
;
LOCATION"R585"
$SEC"1"
CDS_SEC"1"
TOLERANCE"1%"
VALUE"10K"
PACK_TYPE"0402LF"
WATTAGE"1/16W"
MATERIAL"CHIP"
CDS_LIB"pure_quanta"
PART_NUMBER"CS31002FB08";
"A"
$PN"1"46;
"B"
$PN"2"1;
%"UNIVERSAL_GND"
"1","(-3925,850)","0","pure_quanta_power","I16";
;
CDS_LIB"pure_quanta_power"
HDL_POWER"GND";
"A"1;
%"Q_RES"
"2","(-3925,1575)","0","pure_quanta","I17";
;
LOCATION"R580"
$SEC"1"
CDS_SEC"1"
WATTAGE"1/16W"
TOLERANCE"1%"
MATERIAL"CHIP"
PACK_TYPE"0402LF"
VALUE"10K"
CDS_LIB"pure_quanta"
PART_NUMBER"CS31002FB08";
"A"
$PN"1"2;
"B"
$PN"2"46;
%"UNIVERSAL_POWER"
"1","(-3925,1875)","0","pure_quanta_power","I18";
;
HDL_POWER"P3V3_AUX"
CDS_LIB"pure_quanta_power";
"A"2;
%"Q_INDUCTOR"
"1","(-8450,5850)","0","pure_quanta","I2";
;
LOCATION"L1"
$SEC"1"
CDS_SEC"1"
MATERIAL"IND"
PACK_TYPE"SMLF"
VALUE"FCM2012KF-601T/0.5A"
CDS_LIB"pure_quanta"
NEEDS_NO_SIZE"TRUE"
PART_NUMBER"CX601T05003";
"1"
$PN"1"20;
"2"
$PN"2"11;
%"Q_RES"
"1","(-7550,5000)","0","pure_quanta","I20";
;
LOCATION"R555"
$SEC"1"
CDS_SEC"1"
WATTAGE"1/10W"
PACK_TYPE"0603LF"
VALUE"1"
MATERIAL"CHIP"
TOLERANCE"1%"
CDS_LIB"pure_quanta"
PART_NUMBER"CS-1003F900";
"B"
$PN"2"18;
"A"
$PN"1"11;
%"Q_RES"
"1","(-7600,5825)","0","pure_quanta","I21";
;
LOCATION"R586"
$SEC"1"
CDS_SEC"1"
WATTAGE"1/10W"
MATERIAL"CHIP"
VALUE"1"
PACK_TYPE"0603LF"
TOLERANCE"1%"
CDS_LIB"pure_quanta"
PART_NUMBER"CS-1003F900";
"B"
$PN"2"17;
"A"
$PN"1"11;
%"UNIVERSAL_GND"
"1","(-6825,5275)","0","pure_quanta_power","I23";
;
CDS_LIB"pure_quanta_power"
HDL_POWER"GND";
"A"21;
%"Q_CAP"
"1","(-6825,5650)","0","pure_quanta","I24";
;
LOCATION"C68"
$SEC"1"
CDS_SEC"1"
VOLTAGE"25V"
MATERIAL"X7R"
VALUE"0.1UF"
TOLERANCE"10%"
PACK_TYPE"0402"
CDS_LIB"pure_quanta"
PART_NUMBER"CH4104K1B00";
"B"
$PN"2"21;
"A"
$PN"1"17;
%"UNIVERSAL_GND"
"1","(-6800,4475)","0","pure_quanta_power","I25";
;
CDS_LIB"pure_quanta_power"
HDL_POWER"GND";
"A"19;
%"Q_CAP"
"1","(-6800,4850)","0","pure_quanta","I26";
;
LOCATION"C84"
$SEC"1"
CDS_SEC"1"
PACK_TYPE"0402"
TOLERANCE"10%"
MATERIAL"X7R"
VOLTAGE"25V"
VALUE"0.1UF"
CDS_LIB"pure_quanta"
PART_NUMBER"CH4104K1B00";
"B"
$PN"2"19;
"A"
$PN"1"18;
%"UNIVERSAL_POWER"
"1","(-5850,4075)","0","pure_quanta_power","I27";
;
HDL_POWER"P3V3_9ZXL045_P1_VDDR"
CDS_LIB"pure_quanta_power";
"A"3;
%"UNIVERSAL_POWER"
"1","(-6800,5100)","0","pure_quanta_power","I28";
;
HDL_POWER"P3V3_9ZXL045_P1_VDDR"
CDS_LIB"pure_quanta_power";
"A"18;
%"UNIVERSAL_POWER"
"1","(-6825,5900)","0","pure_quanta_power","I29";
;
HDL_POWER"P3V3_9ZXL045_P1_VDDA"
CDS_LIB"pure_quanta_power";
"A"17;
%"UNIVERSAL_GND"
"1","(-5925,900)","0","pure_quanta_power","I3";
;
CDS_LIB"pure_quanta_power"
HDL_POWER"GND";
"A"4;
%"UNIVERSAL_POWER"
"1","(-5450,4375)","0","pure_quanta_power","I30";
;
HDL_POWER"P3V3_9ZXL045_P1_VDD"
CDS_LIB"pure_quanta_power";
"A"16;
%"UNIVERSAL_POWER"
"1","(-5575,5625)","0","pure_quanta_power","I31";
;
HDL_POWER"P3V3_AUX"
CDS_LIB"pure_quanta_power";
"A"22;
%"Q_INDUCTOR"
"1","(-5125,5525)","0","pure_quanta","I32";
;
LOCATION"L2"
$SEC"1"
CDS_SEC"1"
MATERIAL"IND"
PACK_TYPE"SMLF"
VALUE"FCM2012KF-601T/0.5A"
NEEDS_NO_SIZE"TRUE"
CDS_LIB"pure_quanta"
PART_NUMBER"CX601T05003";
"1"
$PN"1"22;
"2"
$PN"2"13;
%"Q_CAP"
"1","(-4250,5300)","0","pure_quanta","I34";
;
LOCATION"C58"
$SEC"1"
CDS_SEC"1"
PACK_TYPE"0402"
MATERIAL"X7R"
VOLTAGE"25V"
TOLERANCE"10%"
VALUE"0.1UF"
CDS_LIB"pure_quanta"
PART_NUMBER"CH4104K1B00";
"B"
$PN"2"14;
"A"
$PN"1"13;
%"Q_CAP"
"1","(-4000,5300)","0","pure_quanta","I35";
;
LOCATION"C90"
$SEC"1"
CDS_SEC"1"
VOLTAGE"25V"
PACK_TYPE"0402"
TOLERANCE"10%"
MATERIAL"X7R"
VALUE"0.1UF"
CDS_LIB"pure_quanta"
PART_NUMBER"CH4104K1B00";
"B"
$PN"2"14;
"A"
$PN"1"13;
%"Q_CAP"
"1","(-3750,5300)","0","pure_quanta","I36";
;
LOCATION"C98"
$SEC"1"
CDS_SEC"1"
MATERIAL"X7R"
PACK_TYPE"0402"
TOLERANCE"10%"
VOLTAGE"25V"
VALUE"0.1UF"
CDS_LIB"pure_quanta"
PART_NUMBER"CH4104K1B00";
"B"
$PN"2"14;
"A"
$PN"1"13;
%"UNIVERSAL_GND"
"1","(-3700,2550)","0","pure_quanta_power","I38";
;
CDS_LIB"pure_quanta_power"
HDL_POWER"GND";
"A"15;
%"Q_RES"
"2","(-2550,2775)","0","pure_quanta","I49";
;
LOCATION"R592"
$SEC"1"
CDS_SEC"1"
PACK_TYPE"0402LF"
MATERIAL"CHIP"
VALUE"10K"
TOLERANCE"1%"
WATTAGE"1/16W"
CDS_LIB"pure_quanta"
PART_NUMBER"CS31002FB08";
"A"
$PN"1"25;
"B"
$PN"2"12;
%"Q_RES"
"2","(-2350,2775)","0","pure_quanta","I50";
;
LOCATION"R593"
$SEC"1"
CDS_SEC"1"
MATERIAL"CHIP"
PACK_TYPE"0402LF"
TOLERANCE"1%"
WATTAGE"1/16W"
VALUE"10K"
CDS_LIB"pure_quanta"
PART_NUMBER"CS31002FB08";
"A"
$PN"1"26;
"B"
$PN"2"12;
%"Q_RES"
"2","(-2125,2775)","0","pure_quanta","I51";
;
LOCATION"R594"
$SEC"1"
CDS_SEC"1"
PACK_TYPE"0402LF"
MATERIAL"CHIP"
VALUE"10K"
WATTAGE"1/16W"
TOLERANCE"1%"
CDS_LIB"pure_quanta"
PART_NUMBER"CS31002FB08";
"A"
$PN"1"29;
"B"
$PN"2"12;
%"UNIVERSAL_POWER"
"1","(-3575,4375)","0","pure_quanta_power","I56";
;
HDL_POWER"P3V3_9ZXL045_P1_VDDA"
CDS_LIB"pure_quanta_power";
"A"5;
%"Q_CAP"
"1","(-3500,5300)","0","pure_quanta","I58";
;
LOCATION"C99"
$SEC"1"
CDS_SEC"1"
MATERIAL"X7R"
TOLERANCE"10%"
VOLTAGE"25V"
PACK_TYPE"0402"
VALUE"0.1UF"
CDS_LIB"pure_quanta"
PART_NUMBER"CH4104K1B00";
"B"
$PN"2"14;
"A"
$PN"1"13;
%"UNIVERSAL_GND"
"1","(-3225,4950)","0","pure_quanta_power","I59";
;
CDS_LIB"pure_quanta_power"
HDL_POWER"GND";
"A"14;
%"Q_CAP"
"1","(-3225,5300)","0","pure_quanta","I60";
;
LOCATION"C75"
$SEC"1"
CDS_SEC"1"
PACK_TYPE"0402"
MATERIAL"X7R"
TOLERANCE"10%"
VALUE"0.1UF"
VOLTAGE"25V"
CDS_LIB"pure_quanta"
PART_NUMBER"CH4104K1B00";
"B"
$PN"2"14;
"A"
$PN"1"13;
%"UNIVERSAL_POWER"
"1","(-3225,5650)","0","pure_quanta_power","I61";
;
HDL_POWER"P3V3_9ZXL045_P1_VDD"
CDS_LIB"pure_quanta_power";
"A"13;
%"9ZXL0451EKILFT"
"1","(-4525,3475)","0","pure_quanta","I63";
;
LOCATION"U10"
$SEC"1"
CDS_SEC"1"
VALUE"9ZXL0451EKILFT"
MATERIAL"IC"
PART_TYPE"SMLF"
CDS_LIB"pure_quanta"
NEEDS_NO_SIZE"TRUE"
CDS_LMAN_SYM_OUTLINE"-475,725,475,-725"
PART_NUMBER"AL000451003";
"VSADR0_TRI"
$PN"5"35;
"NC2"
$PN"17"39;
"NC3"
$PN"30"28;
"VDD0"
$PN"12"16;
"DIF3"
$PN"27"44;
"DIF1"
$PN"19"38;
"EPAD_GND"
$PN"33"15;
"^HIBW_BYPM_LOBW# \B"
$PN"32"10;
"VDD1"
$PN"16"16;
"VDDA"
$PN"31"5;
"NC0"
$PN"10"27;
"DIF3# \B"
$PN"28"30;
"DIF2# \B"
$PN"23"45;
"VOE2# \B"
$PN"24"25;
"DIF2"
$PN"22"43;
"DIF1# \B"
$PN"20"8;
"VOE1# \B"
$PN"18"26;
"DIF0"
$PN"13"9;
"DIF0# \B"
$PN"14"42;
"^CKPWRGD_PD# \B"
$PN"1"23;
"VDD2"
$PN"21"16;
"SMBCLK"
$PN"7"33;
"FBOUT_NC# \B"
$PN"8"31;
"NC1"
$PN"11"40;
"SMBDAT"
$PN"6"34;
"VOE3# \B"
$PN"26"24;
"VOE0# \B"
$PN"15"29;
"FBOUT_NC"
$PN"9"32;
"VDD4"
$PN"29"16;
"VDD3"
$PN"25"16;
"VDDR"
$PN"2"3;
"DIF_IN# \B"
$PN"4"36;
"DIF_IN"
$PN"3"37;
%"Q_RES"
"2","(-5925,1150)","0","pure_quanta","I64";
;
LOCATION"R579"
$SEC"1"
CDS_SEC"1"
TOLERANCE"1%"
PACK_TYPE"0402LF"
VALUE"4.75K"
WATTAGE"1/16W"
MATERIAL"CHIP"
CDS_LIB"pure_quanta"
PART_NUMBER"CS24752FB03";
"A"
$PN"1"41;
"B"
$PN"2"4;
%"Q_RES"
"2","(-5925,1575)","0","pure_quanta","I65";
;
LOCATION"R578"
$SEC"1"
CDS_SEC"1"
WATTAGE"1/16W"
VALUE"4.75K"
MATERIAL"EMPTY"
TOLERANCE"1%"
PACK_TYPE"0402LF"
CDS_LIB"pure_quanta"
PART_NUMBER"CS24752FB03";
"A"
$PN"1"6;
"B"
$PN"2"41;
%"UNIVERSAL_POWER"
"1","(-5925,1925)","0","pure_quanta_power","I7";
;
HDL_POWER"P3V3_AUX"
CDS_LIB"pure_quanta_power";
"A"6;
%"Q_RES"
"2","(-2750,2775)","0","pure_quanta","I76";
;
LOCATION"R6803"
$SEC"1"
CDS_SEC"1"
WATTAGE"1/16W"
TOLERANCE"1%"
VALUE"10K"
MATERIAL"CHIP"
PACK_TYPE"0402LF"
CDS_LIB"pure_quanta"
PART_NUMBER"CS31002FB08";
"A"
$PN"1"24;
"B"
$PN"2"12;
%"Q_CAP"
"1","(-7175,5650)","0","pure_quanta","I77";
;
LOCATION"C82"
$SEC"1"
CDS_SEC"1"
TOLERANCE"20%"
MATERIAL"X6S"
PACK_TYPE"C0402"
VOLTAGE"6.3V"
VALUE"10UF"
CDS_LIB"pure_quanta"
PART_NUMBER"CH6101MEB01";
"B"
$PN"2"21;
"A"
$PN"1"17;
%"Q_CAP"
"1","(-7150,4850)","0","pure_quanta","I78";
;
LOCATION"C83"
$SEC"1"
CDS_SEC"1"
TOLERANCE"20%"
MATERIAL"X6S"
PACK_TYPE"C0402"
VOLTAGE"6.3V"
VALUE"10UF"
CDS_LIB"pure_quanta"
PART_NUMBER"CH6101MEB01";
"B"
$PN"2"19;
"A"
$PN"1"18;
%"Q_CAP"
"1","(-4600,5300)","0","pure_quanta","I79";
;
LOCATION"C28"
$SEC"1"
CDS_SEC"1"
MATERIAL"X6S"
VALUE"10UF"
VOLTAGE"6.3V"
PACK_TYPE"C0402"
TOLERANCE"20%"
CDS_LIB"pure_quanta"
PART_NUMBER"CH6101MEB01";
"B"
$PN"2"14;
"A"
$PN"1"13;
%"UNIVERSAL_GND"
"1","(-2125,2350)","0","pure_quanta_power","I80";
;
CDS_LIB"pure_quanta_power"
HDL_POWER"GND";
"A"12;
%"Q_RES"
"2","(-7000,3500)","0","pure_quanta","I81";
;
LOCATION"R560"
$SEC"1"
CDS_SEC"1"
WATTAGE"1/16W"
TOLERANCE"1%"
VALUE"10K"
MATERIAL"CHIP"
PACK_TYPE"0402LF"
CDS_LIB"pure_quanta"
PART_NUMBER"CS31002FB08";
"A"
$PN"1"7;
"B"
$PN"2"23;
%"UNIVERSAL_POWER"
"1","(-7000,3800)","0","pure_quanta_power","I82";
;
HDL_POWER"P3V3_AUX"
CDS_LIB"pure_quanta_power";
"A"7;
END.
